# S9S_MB_2U (Grand Teton) — schematic netlist excerpt (pin names and nets, part order shuffled) for the footprints in the layout excerpt that follows; sources: Cadence DE-HDL packaged netlist, KiCad conversion of 03242023_DA0F0TMBIJ0_F0T_Motherboard_J_brd_V01_OCP.brd

R2829  Q_RES  100K 1% EMPTY  pkg 0402LF  page 148 : A = RST_BMC_FROM_SWB_N ; B = GND
PC558_P1_2  Q_CAP  2.2UF 10V 10% X6S  pkg C0402  page 285 : A = PVCCIN_CPU1_PVCC ; B = GND

(kicad_pcb
	(version 20260206)
	(generator "pcbnew")
	(generator_version "10.0")
	(general
		(thickness 1.6)
		(legacy_teardrops no)
	)
	(paper "A4")
	(title_block
		(title "03242023_DA0F0TMBIJ0_F0T_Motherboard_J_brd_V01_OCP.brd")
		(comment 1 "Grand Teton / footprints 2001-2002 of 6105")
	)
	(layers
		(0 "F.Cu" signal "TOP")
		(4 "In1.Cu" signal "GND")
		(6 "In2.Cu" signal "IN1")
		(8 "In3.Cu" signal "GND1")
		(10 "In4.Cu" signal "IN2")
		(12 "In5.Cu" signal "GND2")
		(14 "In6.Cu" signal "IN3")
		(16 "In7.Cu" signal "GND3")
		(18 "In8.Cu" signal "VCC")
		(20 "In9.Cu" signal "VCC1")
		(22 "In10.Cu" signal "GND4")
		(24 "In11.Cu" signal "IN4")
		(26 "In12.Cu" signal "GND5")
		(28 "In13.Cu" signal "IN5")
		(30 "In14.Cu" signal "GND6")
		(32 "In15.Cu" signal "IN6")
		(34 "In16.Cu" signal "GND7")
		(2 "B.Cu" signal "BOTTOM")
		(9 "F.Adhes" user "F.Adhesive")
		(11 "B.Adhes" user "B.Adhesive")
		(13 "F.Paste" user "Package Geometry/Pastemask Top")
		(15 "B.Paste" user "Package Geometry/Pastemask Bottom")
		(5 "F.SilkS" user "Ref Des/Silkscreen Top")
		(7 "B.SilkS" user "Ref Des/Silkscreen Bottom")
		(1 "F.Mask" user "Board Geometry/Soldermask Top")
		(3 "B.Mask" user "Board Geometry/Soldermask Bottom")
		(17 "Dwgs.User" user "User.Drawings")
		(19 "Cmts.User" user "User.Comments")
		(21 "Eco1.User" user "User.Eco1")
		(23 "Eco2.User" user "User.Eco2")
		(25 "Edge.Cuts" user "Board Geometry/Outline")
		(27 "Margin" user)
		(31 "F.CrtYd" user "Package Geometry/Place Bound Top")
		(29 "B.CrtYd" user "Package Geometry/Place Bound Bottom")
		(35 "F.Fab" user "Ref Des/Assembly Top")
		(33 "B.Fab" user "Ref Des/Assembly Bottom")
	)
	(footprint ""
		(layer "F.Cu")
		(at 101.58349 -333.525368 -90)
		(property "Reference" "PC558_P1_2"
			(at 0 0 270)
			(layer "F.SilkS")
			(hide yes)
			(effects
				(font
					(size 1.27 1.27)
				)
			)
		)
		(property "Value" ""
			(at 0 0 270)
			(layer "F.Fab")
			(effects
				(font
					(size 1.27 1.27)
				)
			)
		)
		(duplicate_pad_numbers_are_jumpers no)
		(fp_line
			(start -0.7874 0.4064)
			(end -0.7874 -0.4064)
			(stroke
				(width 0.1524)
				(type default)
			)
			(layer "F.SilkS")
		)
		(fp_line
			(start 0.7874 0.4064)
			(end -0.7874 0.4064)
			(stroke
				(width 0.1524)
				(type default)
			)
			(layer "F.SilkS")
		)
		(fp_line
			(start -0.7874 -0.4064)
			(end 0.7874 -0.4064)
			(stroke
				(width 0.1524)
				(type default)
			)
			(layer "F.SilkS")
		)
		(fp_line
			(start 0.7874 -0.4064)
			(end 0.7874 0.4064)
			(stroke
				(width 0.1524)
				(type default)
			)
			(layer "F.SilkS")
		)
		(fp_line
			(start -0.67945 0.3048)
			(end -0.67945 -0.305054)
			(stroke
				(width 0.1)
				(type default)
			)
			(layer "F.Fab")
		)
		(fp_line
			(start -0.12065 0.3048)
			(end -0.67945 0.3048)
			(stroke
				(width 0.1)
				(type default)
			)
			(layer "F.Fab")
		)
		(fp_line
			(start 0.120396 0.3048)
			(end 0.120396 0.2794)
			(stroke
				(width 0.1)
				(type default)
			)
			(layer "F.Fab")
		)
		(fp_line
			(start 0.67945 0.3048)
			(end 0.120396 0.3048)
			(stroke
				(width 0.1)
				(type default)
			)
			(layer "F.Fab")
		)
		(fp_line
			(start -0.12065 0.2794)
			(end -0.12065 0.3048)
			(stroke
				(width 0.1)
				(type default)
			)
			(layer "F.Fab")
		)
		(fp_line
			(start 0.120396 0.2794)
			(end -0.12065 0.2794)
			(stroke
				(width 0.1)
				(type default)
			)
			(layer "F.Fab")
		)
		(fp_line
			(start -0.12065 -0.2794)
			(end 0.12065 -0.2794)
			(stroke
				(width 0.1)
				(type default)
			)
			(layer "F.Fab")
		)
		(fp_line
			(start 0.12065 -0.2794)
			(end 0.12065 -0.3048)
			(stroke
				(width 0.1)
				(type default)
			)
			(layer "F.Fab")
		)
		(fp_line
			(start 0.12065 -0.3048)
			(end 0.67945 -0.3048)
			(stroke
				(width 0.1)
				(type default)
			)
			(layer "F.Fab")
		)
		(fp_line
			(start 0.67945 -0.3048)
			(end 0.67945 0.3048)
			(stroke
				(width 0.1)
				(type default)
			)
			(layer "F.Fab")
		)
		(fp_line
			(start -0.67945 -0.305054)
			(end -0.12065 -0.305054)
			(stroke
				(width 0.1)
				(type default)
			)
			(layer "F.Fab")
		)
		(fp_line
			(start -0.12065 -0.305054)
			(end -0.12065 -0.2794)
			(stroke
				(width 0.1)
				(type default)
			)
			(layer "F.Fab")
		)
		(pad "1" smd circle
			(at -0.40005 0 270)
			(size 0 0)
			(layers "F.Cu" "F.Mask" "F.Paste")
			(net "PVCCIN_CPU1_PVCC")
		)
		(pad "2" smd circle
			(at 0.40005 0 270)
			(size 0 0)
			(layers "F.Cu" "F.Mask" "F.Paste")
			(net "GND")
		)
	)
	(footprint ""
		(layer "F.Cu")
		(at 424.204892 -382.361948 180)
		(property "Reference" "R2829"
			(at 0 0 180)
			(layer "F.SilkS")
			(hide yes)
			(effects
				(font
					(size 1.27 1.27)
				)
			)
		)
		(property "Value" ""
			(at 0 0 180)
			(layer "F.Fab")
			(effects
				(font
					(size 1.27 1.27)
				)
			)
		)
		(duplicate_pad_numbers_are_jumpers no)
		(fp_line
			(start 0.7874 0.4064)
			(end -0.7874 0.4064)
			(stroke
				(width 0.1524)
				(type default)
			)
			(layer "F.SilkS")
		)
		(fp_line
			(start 0.7874 -0.4064)
			(end 0.7874 0.4064)
			(stroke
				(width 0.1524)
				(type default)
			)
			(layer "F.SilkS")
		)
		(fp_line
			(start -0.7874 0.4064)
			(end -0.7874 -0.4064)
			(stroke
				(width 0.1524)
				(type default)
			)
			(layer "F.SilkS")
		)
		(fp_line
			(start -0.7874 -0.4064)
			(end 0.7874 -0.4064)
			(stroke
				(width 0.1524)
				(type default)
			)
			(layer "F.SilkS")
		)
		(fp_line
			(start 0.67945 0.3048)
			(end 0.120396 0.3048)
			(stroke
				(width 0.1)
				(type default)
			)
			(layer "F.Fab")
		)
		(fp_line
			(start 0.67945 -0.3048)
			(end 0.67945 0.3048)
			(stroke
				(width 0.1)
				(type default)
			)
			(layer "F.Fab")
		)
		(fp_line
			(start 0.12065 -0.2794)
			(end 0.12065 -0.3048)
			(stroke
				(width 0.1)
				(type default)
			)
			(layer "F.Fab")
		)
		(fp_line
			(start 0.12065 -0.3048)
			(end 0.67945 -0.3048)
			(stroke
				(width 0.1)
				(type default)
			)
			(layer "F.Fab")
		)
		(fp_line
			(start 0.120396 0.3048)
			(end 0.120396 0.2794)
			(stroke
				(width 0.1)
				(type default)
			)
			(layer "F.Fab")
		)
		(fp_line
			(start 0.120396 0.2794)
			(end -0.12065 0.2794)
			(stroke
				(width 0.1)
				(type default)
			)
			(layer "F.Fab")
		)
		(fp_line
			(start -0.12065 0.3048)
			(end -0.67945 0.3048)
			(stroke
				(width 0.1)
				(type default)
			)
			(layer "F.Fab")
		)
		(fp_line
			(start -0.12065 0.2794)
			(end -0.12065 0.3048)
			(stroke
				(width 0.1)
				(type default)
			)
			(layer "F.Fab")
		)
		(fp_line
			(start -0.12065 -0.2794)
			(end 0.12065 -0.2794)
			(stroke
				(width 0.1)
				(type default)
			)
			(layer "F.Fab")
		)
		(fp_line
			(start -0.12065 -0.305054)
			(end -0.12065 -0.2794)
			(stroke
				(width 0.1)
				(type default)
			)
			(layer "F.Fab")
		)
		(fp_line
			(start -0.67945 0.3048)
			(end -0.67945 -0.305054)
			(stroke
				(width 0.1)
				(type default)
			)
			(layer "F.Fab")
		)
		(fp_line
			(start -0.67945 -0.305054)
			(end -0.12065 -0.305054)
			(stroke
				(width 0.1)
				(type default)
			)
			(layer "F.Fab")
		)
		(pad "1" smd circle
			(at -0.40005 0 180)
			(size 0 0)
			(layers "F.Cu" "F.Mask" "F.Paste")
			(net "RST_BMC_FROM_SWB_N")
		)
		(pad "2" smd circle
			(at 0.40005 0 180)
			(size 0 0)
			(layers "F.Cu" "F.Mask" "F.Paste")
			(net "GND")
		)
	)
)
